(kicad_pcb
	(version 20260206)
	(generator "pcbnew")
	(generator_version "10.0")
	(general
		(thickness 1.6)
		(legacy_teardrops no)
	)
	(paper "A4")
	(title_block
		(title "v1-chassis-manager — T6M_CM_d_v01_1031_1645.brd")
		(comment 1 "Open CloudServer (Microsoft) / footprints 1865-1874 of 2512")
	)
	(layers
		(0 "F.Cu" signal "TOP")
		(4 "In1.Cu" signal "GND1")
		(6 "In2.Cu" signal "IN1")
		(8 "In3.Cu" signal "VCC1")
		(10 "In4.Cu" signal "VCC2")
		(12 "In5.Cu" signal "GND2")
		(14 "In6.Cu" signal "IN2")
		(16 "In7.Cu" signal "IN3")
		(18 "In8.Cu" signal "GND3")
		(2 "B.Cu" signal "BOTTOM")
		(9 "F.Adhes" user "F.Adhesive")
		(11 "B.Adhes" user "B.Adhesive")
		(13 "F.Paste" user "Package Geometry/Pastemask Top")
		(15 "B.Paste" user "Package Geometry/Pastemask Bottom")
		(5 "F.SilkS" user "Ref Des/Silkscreen Top")
		(7 "B.SilkS" user "Ref Des/Silkscreen Bottom")
		(1 "F.Mask" user "Board Geometry/Soldermask Top")
		(3 "B.Mask" user "Board Geometry/Soldermask Bottom")
		(17 "Dwgs.User" user "User.Drawings")
		(19 "Cmts.User" user "User.Comments")
		(21 "Eco1.User" user "User.Eco1")
		(23 "Eco2.User" user "User.Eco2")
		(25 "Edge.Cuts" user "Board Geometry/Outline")
		(27 "Margin" user)
		(31 "F.CrtYd" user "Package Geometry/Place Bound Top")
		(29 "B.CrtYd" user "Package Geometry/Place Bound Bottom")
		(35 "F.Fab" user "Ref Des/Assembly Top")
		(33 "B.Fab" user "Ref Des/Assembly Bottom")
	)
	(footprint ""
		(layer "B.Cu")
		(at 36.590732 -94.40037 -90)
		(property "Reference" "C28"
			(at 4.703318 4.676394 270)
			(unlocked yes)
			(layer "B.SilkS")
			(effects
				(font
					(size 0.7874 0.5842)
					(thickness 0.1524)
				)
				(justify left mirror)
			)
		)
		(property "Value" ""
			(at 0 0 90)
			(layer "B.Fab")
			(effects
				(font
					(size 1.27 1.27)
				)
				(justify mirror)
			)
		)
		(duplicate_pad_numbers_are_jumpers no)
		(fp_line
			(start -0.7874 0.4064)
			(end 0.7874 0.4064)
			(stroke
				(width 0.1524)
				(type default)
			)
			(layer "B.SilkS")
		)
		(fp_line
			(start 0.7874 0.4064)
			(end 0.7874 -0.4064)
			(stroke
				(width 0.1524)
				(type default)
			)
			(layer "B.SilkS")
		)
		(fp_line
			(start 0 0.381)
			(end 0 -0.381)
			(stroke
				(width 0.1524)
				(type default)
			)
			(layer "B.SilkS")
		)
		(fp_line
			(start -0.7874 -0.4064)
			(end -0.7874 0.4064)
			(stroke
				(width 0.1524)
				(type default)
			)
			(layer "B.SilkS")
		)
		(fp_line
			(start 0.7874 -0.4064)
			(end -0.7874 -0.4064)
			(stroke
				(width 0.1524)
				(type default)
			)
			(layer "B.SilkS")
		)
		(fp_poly
			(pts
				(xy 0.5334 0.254) (xy 0.635 0.254) (xy 0.635 0.2286) (xy 0.635 -0.254) (xy 0.5334 -0.254) (xy 0.5334 -0.2794)
				(xy -0.5334 -0.2794) (xy -0.5334 -0.254) (xy -0.635 -0.254) (xy -0.635 0.254) (xy -0.5334 0.254)
				(xy -0.5334 0.2794) (xy 0.508 0.2794) (xy 0.5334 0.2794)
			)
			(stroke
				(width 0)
				(type default)
			)
			(fill no)
			(layer "B.CrtYd")
		)
		(pad "1" smd rect
			(at -0.40005 0 90)
			(size 0.4572 0.508)
			(layers "B.Cu" "B.Mask" "B.Paste")
			(net "GND")
		)
		(pad "2" smd rect
			(at 0.40005 0 90)
			(size 0.4572 0.508)
			(layers "B.Cu" "B.Mask" "B.Paste")
			(net "SMB_CPU_NODE1_MEM_ICS_CLK_R")
		)
	)
	(footprint ""
		(layer "B.Cu")
		(at 55.993538 -82.579718 -90)
		(property "Reference" "C38"
			(at -0.971296 0.116078 270)
			(unlocked yes)
			(layer "B.SilkS")
			(effects
				(font
					(size 0.7874 0.5842)
					(thickness 0.1524)
				)
				(justify left mirror)
			)
		)
		(property "Value" ""
			(at 0 0 90)
			(layer "B.Fab")
			(effects
				(font
					(size 1.27 1.27)
				)
				(justify mirror)
			)
		)
		(duplicate_pad_numbers_are_jumpers no)
		(fp_line
			(start -0.7874 0.4064)
			(end 0.7874 0.4064)
			(stroke
				(width 0.1524)
				(type default)
			)
			(layer "B.SilkS")
		)
		(fp_line
			(start 0.7874 0.4064)
			(end 0.7874 -0.4064)
			(stroke
				(width 0.1524)
				(type default)
			)
			(layer "B.SilkS")
		)
		(fp_line
			(start 0 0.381)
			(end 0 -0.381)
			(stroke
				(width 0.1524)
				(type default)
			)
			(layer "B.SilkS")
		)
		(fp_line
			(start -0.7874 -0.4064)
			(end -0.7874 0.4064)
			(stroke
				(width 0.1524)
				(type default)
			)
			(layer "B.SilkS")
		)
		(fp_line
			(start 0.7874 -0.4064)
			(end -0.7874 -0.4064)
			(stroke
				(width 0.1524)
				(type default)
			)
			(layer "B.SilkS")
		)
		(fp_poly
			(pts
				(xy 0.5334 0.254) (xy 0.635 0.254) (xy 0.635 0.2286) (xy 0.635 -0.254) (xy 0.5334 -0.254) (xy 0.5334 -0.2794)
				(xy -0.5334 -0.2794) (xy -0.5334 -0.254) (xy -0.635 -0.254) (xy -0.635 0.254) (xy -0.5334 0.254)
				(xy -0.5334 0.2794) (xy 0.508 0.2794) (xy 0.5334 0.2794)
			)
			(stroke
				(width 0)
				(type default)
			)
			(fill no)
			(layer "B.CrtYd")
		)
		(pad "1" smd rect
			(at -0.40005 0 90)
			(size 0.4572 0.508)
			(layers "B.Cu" "B.Mask" "B.Paste")
			(net "P1V8_NODE1")
		)
		(pad "2" smd rect
			(at 0.40005 0 90)
			(size 0.4572 0.508)
			(layers "B.Cu" "B.Mask" "B.Paste")
			(net "GND")
		)
	)
	(footprint ""
		(layer "B.Cu")
		(at 118.47576 -188.126624 -90)
		(property "Reference" "C641"
			(at -4.080256 -0.707644 270)
			(unlocked yes)
			(layer "B.SilkS")
			(effects
				(font
					(size 0.7874 0.5842)
					(thickness 0.1524)
				)
				(justify left mirror)
			)
		)
		(property "Value" ""
			(at 0 0 90)
			(layer "B.Fab")
			(effects
				(font
					(size 1.27 1.27)
				)
				(justify mirror)
			)
		)
		(duplicate_pad_numbers_are_jumpers no)
		(fp_line
			(start -0.7874 0.406146)
			(end 0.7874 0.406146)
			(stroke
				(width 0.1524)
				(type default)
			)
			(layer "B.SilkS")
		)
		(fp_line
			(start 0.7874 0.406146)
			(end 0.7874 -0.406146)
			(stroke
				(width 0.1524)
				(type default)
			)
			(layer "B.SilkS")
		)
		(fp_line
			(start 0 0.381)
			(end 0 -0.381)
			(stroke
				(width 0.1524)
				(type default)
			)
			(layer "B.SilkS")
		)
		(fp_line
			(start -0.7874 -0.406146)
			(end -0.7874 0.406146)
			(stroke
				(width 0.1524)
				(type default)
			)
			(layer "B.SilkS")
		)
		(fp_line
			(start 0.7874 -0.406146)
			(end -0.7874 -0.406146)
			(stroke
				(width 0.1524)
				(type default)
			)
			(layer "B.SilkS")
		)
		(fp_poly
			(pts
				(xy 0.5334 0.254) (xy 0.635 0.254) (xy 0.635 0.2286) (xy 0.635 -0.254) (xy 0.5334 -0.254) (xy 0.5334 -0.2794)
				(xy -0.5334 -0.2794) (xy -0.5334 -0.254) (xy -0.635 -0.254) (xy -0.635 0.254) (xy -0.5334 0.254)
				(xy -0.5334 0.2794) (xy 0.508 0.2794) (xy 0.5334 0.2794)
			)
			(stroke
				(width 0)
				(type default)
			)
			(fill no)
			(layer "B.CrtYd")
		)
		(pad "1" smd rect
			(at -0.40005 0 90)
			(size 0.4572 0.508)
			(layers "B.Cu" "B.Mask" "B.Paste")
			(net "T7_NODE3_EN_R")
		)
		(pad "2" smd rect
			(at 0.40005 0 90)
			(size 0.4572 0.508)
			(layers "B.Cu" "B.Mask" "B.Paste")
			(net "GND")
		)
	)
	(footprint ""
		(layer "B.Cu")
		(at 130.570986 -58.039 90)
		(property "Reference" "C599"
			(at 1.143 0.339344 270)
			(unlocked yes)
			(layer "B.SilkS")
			(effects
				(font
					(size 0.7874 0.5842)
					(thickness 0.1524)
				)
				(justify left mirror)
			)
		)
		(property "Value" ""
			(at 0 0 90)
			(layer "B.Fab")
			(effects
				(font
					(size 1.27 1.27)
				)
				(justify mirror)
			)
		)
		(duplicate_pad_numbers_are_jumpers no)
		(fp_line
			(start 0.7874 -0.4064)
			(end -0.7874 -0.4064)
			(stroke
				(width 0.1524)
				(type default)
			)
			(layer "B.SilkS")
		)
		(fp_line
			(start -0.7874 -0.4064)
			(end -0.7874 0.4064)
			(stroke
				(width 0.1524)
				(type default)
			)
			(layer "B.SilkS")
		)
		(fp_line
			(start 0 0.381)
			(end 0 -0.381)
			(stroke
				(width 0.1524)
				(type default)
			)
			(layer "B.SilkS")
		)
		(fp_line
			(start 0.7874 0.4064)
			(end 0.7874 -0.4064)
			(stroke
				(width 0.1524)
				(type default)
			)
			(layer "B.SilkS")
		)
		(fp_line
			(start -0.7874 0.4064)
			(end 0.7874 0.4064)
			(stroke
				(width 0.1524)
				(type default)
			)
			(layer "B.SilkS")
		)
		(fp_poly
			(pts
				(xy 0.5334 0.254) (xy 0.635 0.254) (xy 0.635 0.2286) (xy 0.635 -0.254) (xy 0.5334 -0.254) (xy 0.5334 -0.2794)
				(xy -0.5334 -0.2794) (xy -0.5334 -0.254) (xy -0.635 -0.254) (xy -0.635 0.254) (xy -0.5334 0.254)
				(xy -0.5334 0.2794) (xy 0.508 0.2794) (xy 0.5334 0.2794)
			)
			(stroke
				(width 0)
				(type default)
			)
			(fill no)
			(layer "B.CrtYd")
		)
		(pad "1" smd rect
			(at -0.40005 0 270)
			(size 0.4572 0.508)
			(layers "B.Cu" "B.Mask" "B.Paste")
			(net "P3V3_NODE1")
		)
		(pad "2" smd rect
			(at 0.40005 0 270)
			(size 0.4572 0.508)
			(layers "B.Cu" "B.Mask" "B.Paste")
			(net "GND")
		)
	)
	(footprint ""
		(layer "B.Cu")
		(at 70.159372 -80.514698 90)
		(property "Reference" "C71"
			(at -32.158686 -14.55039 270)
			(unlocked yes)
			(layer "B.SilkS")
			(effects
				(font
					(size 0.7874 0.5842)
					(thickness 0.1524)
				)
				(justify left mirror)
			)
		)
		(property "Value" ""
			(at 0 0 90)
			(layer "B.Fab")
			(effects
				(font
					(size 1.27 1.27)
				)
				(justify mirror)
			)
		)
		(duplicate_pad_numbers_are_jumpers no)
		(fp_line
			(start 0.7874 -0.4064)
			(end -0.7874 -0.4064)
			(stroke
				(width 0.1524)
				(type default)
			)
			(layer "B.SilkS")
		)
		(fp_line
			(start -0.7874 -0.4064)
			(end -0.7874 0.4064)
			(stroke
				(width 0.1524)
				(type default)
			)
			(layer "B.SilkS")
		)
		(fp_line
			(start 0 0.381)
			(end 0 -0.381)
			(stroke
				(width 0.1524)
				(type default)
			)
			(layer "B.SilkS")
		)
		(fp_line
			(start 0.7874 0.4064)
			(end 0.7874 -0.4064)
			(stroke
				(width 0.1524)
				(type default)
			)
			(layer "B.SilkS")
		)
		(fp_line
			(start -0.7874 0.4064)
			(end 0.7874 0.4064)
			(stroke
				(width 0.1524)
				(type default)
			)
			(layer "B.SilkS")
		)
		(fp_poly
			(pts
				(xy 0.5334 0.254) (xy 0.635 0.254) (xy 0.635 0.2286) (xy 0.635 -0.254) (xy 0.5334 -0.254) (xy 0.5334 -0.2794)
				(xy -0.5334 -0.2794) (xy -0.5334 -0.254) (xy -0.635 -0.254) (xy -0.635 0.254) (xy -0.5334 0.254)
				(xy -0.5334 0.2794) (xy 0.508 0.2794) (xy 0.5334 0.2794)
			)
			(stroke
				(width 0)
				(type default)
			)
			(fill no)
			(layer "B.CrtYd")
		)
		(pad "1" smd rect
			(at -0.40005 0 270)
			(size 0.4572 0.508)
			(layers "B.Cu" "B.Mask" "B.Paste")
			(net "PV_VCCP_NODE1")
		)
		(pad "2" smd rect
			(at 0.40005 0 270)
			(size 0.4572 0.508)
			(layers "B.Cu" "B.Mask" "B.Paste")
			(net "GND")
		)
	)
	(footprint ""
		(layer "B.Cu")
		(at 69.326252 -134.473188 180)
		(property "Reference" "C249"
			(at 35.998912 -52.684426 0)
			(unlocked yes)
			(layer "B.SilkS")
			(effects
				(font
					(size 0.7874 0.5842)
					(thickness 0.1524)
				)
				(justify left mirror)
			)
		)
		(property "Value" ""
			(at 0 0 0)
			(layer "B.Fab")
			(effects
				(font
					(size 1.27 1.27)
				)
				(justify mirror)
			)
		)
		(duplicate_pad_numbers_are_jumpers no)
		(fp_line
			(start 0.7874 0.4064)
			(end 0.7874 -0.4064)
			(stroke
				(width 0.1524)
				(type default)
			)
			(layer "B.SilkS")
		)
		(fp_line
			(start 0.7874 -0.4064)
			(end -0.7874 -0.4064)
			(stroke
				(width 0.1524)
				(type default)
			)
			(layer "B.SilkS")
		)
		(fp_line
			(start 0 0.381)
			(end 0 -0.381)
			(stroke
				(width 0.1524)
				(type default)
			)
			(layer "B.SilkS")
		)
		(fp_line
			(start -0.7874 0.4064)
			(end 0.7874 0.4064)
			(stroke
				(width 0.1524)
				(type default)
			)
			(layer "B.SilkS")
		)
		(fp_line
			(start -0.7874 -0.4064)
			(end -0.7874 0.4064)
			(stroke
				(width 0.1524)
				(type default)
			)
			(layer "B.SilkS")
		)
		(fp_poly
			(pts
				(xy 0.5334 0.254) (xy 0.635 0.254) (xy 0.635 0.2286) (xy 0.635 -0.254) (xy 0.5334 -0.254) (xy 0.5334 -0.2794)
				(xy -0.5334 -0.2794) (xy -0.5334 -0.254) (xy -0.635 -0.254) (xy -0.635 0.254) (xy -0.5334 0.254)
				(xy -0.5334 0.2794) (xy 0.508 0.2794) (xy 0.5334 0.2794)
			)
			(stroke
				(width 0)
				(type default)
			)
			(fill no)
			(layer "B.CrtYd")
		)
		(pad "1" smd rect
			(at -0.40005 0)
			(size 0.4572 0.508)
			(layers "B.Cu" "B.Mask" "B.Paste")
			(net "P3V3_NODE1")
		)
		(pad "2" smd rect
			(at 0.40005 0)
			(size 0.4572 0.508)
			(layers "B.Cu" "B.Mask" "B.Paste")
			(net "GND")
		)
	)
	(footprint ""
		(layer "B.Cu")
		(at 149.33676 -187.872624 -90)
		(property "Reference" "C723"
			(at -4.565396 3.09245 270)
			(unlocked yes)
			(layer "B.SilkS")
			(effects
				(font
					(size 0.7874 0.5842)
					(thickness 0.1524)
				)
				(justify left mirror)
			)
		)
		(property "Value" ""
			(at 0 0 90)
			(layer "B.Fab")
			(effects
				(font
					(size 1.27 1.27)
				)
				(justify mirror)
			)
		)
		(duplicate_pad_numbers_are_jumpers no)
		(fp_line
			(start -0.7874 0.4064)
			(end 0.7874 0.4064)
			(stroke
				(width 0.1524)
				(type default)
			)
			(layer "B.SilkS")
		)
		(fp_line
			(start 0.7874 0.4064)
			(end 0.7874 -0.4064)
			(stroke
				(width 0.1524)
				(type default)
			)
			(layer "B.SilkS")
		)
		(fp_line
			(start 0 0.381)
			(end 0 -0.381)
			(stroke
				(width 0.1524)
				(type default)
			)
			(layer "B.SilkS")
		)
		(fp_line
			(start -0.7874 -0.4064)
			(end -0.7874 0.4064)
			(stroke
				(width 0.1524)
				(type default)
			)
			(layer "B.SilkS")
		)
		(fp_line
			(start 0.7874 -0.4064)
			(end -0.7874 -0.4064)
			(stroke
				(width 0.1524)
				(type default)
			)
			(layer "B.SilkS")
		)
		(fp_poly
			(pts
				(xy 0.5334 0.254) (xy 0.635 0.254) (xy 0.635 0.2286) (xy 0.635 -0.254) (xy 0.5334 -0.254) (xy 0.5334 -0.2794)
				(xy -0.5334 -0.2794) (xy -0.5334 -0.254) (xy -0.635 -0.254) (xy -0.635 0.254) (xy -0.5334 0.254)
				(xy -0.5334 0.2794) (xy 0.508 0.2794) (xy 0.5334 0.2794)
			)
			(stroke
				(width 0)
				(type default)
			)
			(fill no)
			(layer "B.CrtYd")
		)
		(pad "1" smd rect
			(at -0.40005 0 90)
			(size 0.4572 0.508)
			(layers "B.Cu" "B.Mask" "B.Paste")
			(net "UART_T11_NODE1_TXD_R")
		)
		(pad "2" smd rect
			(at 0.40005 0 90)
			(size 0.4572 0.508)
			(layers "B.Cu" "B.Mask" "B.Paste")
			(net "GND")
		)
	)
	(footprint ""
		(layer "B.Cu")
		(at 61.462666 -118.910862 -90)
		(property "Reference" "R319"
			(at 5.202682 -0.004064 270)
			(unlocked yes)
			(layer "B.SilkS")
			(effects
				(font
					(size 0.7874 0.5842)
					(thickness 0.1524)
				)
				(justify left mirror)
			)
		)
		(property "Value" ""
			(at 0 0 90)
			(layer "B.Fab")
			(effects
				(font
					(size 1.27 1.27)
				)
				(justify mirror)
			)
		)
		(duplicate_pad_numbers_are_jumpers no)
		(fp_line
			(start -0.7874 0.4064)
			(end 0.7874 0.4064)
			(stroke
				(width 0.1524)
				(type default)
			)
			(layer "B.SilkS")
		)
		(fp_line
			(start 0.7874 0.4064)
			(end 0.7874 -0.4064)
			(stroke
				(width 0.1524)
				(type default)
			)
			(layer "B.SilkS")
		)
		(fp_line
			(start -0.7874 -0.4064)
			(end -0.7874 0.4064)
			(stroke
				(width 0.1524)
				(type default)
			)
			(layer "B.SilkS")
		)
		(fp_line
			(start 0.7874 -0.4064)
			(end -0.7874 -0.4064)
			(stroke
				(width 0.1524)
				(type default)
			)
			(layer "B.SilkS")
		)
		(fp_poly
			(pts
				(xy 0.508 0.2794) (xy 0.508 0.2286) (xy 0.635 0.2286) (xy 0.635 -0.254) (xy 0.5334 -0.254) (xy 0.5334 -0.2794)
				(xy -0.5334 -0.2794) (xy -0.5334 -0.254) (xy -0.635 -0.254) (xy -0.635 0.254) (xy -0.5334 0.254)
				(xy -0.5334 0.2794)
			)
			(stroke
				(width 0)
				(type default)
			)
			(fill no)
			(layer "B.CrtYd")
		)
		(pad "1" smd rect
			(at -0.40005 0 90)
			(size 0.4572 0.508)
			(layers "B.Cu" "B.Mask" "B.Paste")
			(net "P3V3_NODE1")
		)
		(pad "2" smd rect
			(at 0.40005 0 90)
			(size 0.4572 0.508)
			(layers "B.Cu" "B.Mask" "B.Paste")
			(net "BMC_ROMA3")
		)
	)
	(footprint ""
		(layer "B.Cu")
		(at 165.186106 -168.146222 -90)
		(property "Reference" "R1064"
			(at 4.911344 -1.026668 270)
			(unlocked yes)
			(layer "B.SilkS")
			(effects
				(font
					(size 0.7874 0.5842)
					(thickness 0.1524)
				)
				(justify left mirror)
			)
		)
		(property "Value" ""
			(at 0 0 90)
			(layer "B.Fab")
			(effects
				(font
					(size 1.27 1.27)
				)
				(justify mirror)
			)
		)
		(duplicate_pad_numbers_are_jumpers no)
		(fp_line
			(start -0.7874 0.4064)
			(end 0.7874 0.4064)
			(stroke
				(width 0.1524)
				(type default)
			)
			(layer "B.SilkS")
		)
		(fp_line
			(start 0.7874 0.4064)
			(end 0.7874 -0.4064)
			(stroke
				(width 0.1524)
				(type default)
			)
			(layer "B.SilkS")
		)
		(fp_line
			(start -0.7874 -0.4064)
			(end -0.7874 0.4064)
			(stroke
				(width 0.1524)
				(type default)
			)
			(layer "B.SilkS")
		)
		(fp_line
			(start 0.7874 -0.4064)
			(end -0.7874 -0.4064)
			(stroke
				(width 0.1524)
				(type default)
			)
			(layer "B.SilkS")
		)
		(fp_poly
			(pts
				(xy 0.508 0.2794) (xy 0.508 0.2286) (xy 0.635 0.2286) (xy 0.635 -0.254) (xy 0.5334 -0.254) (xy 0.5334 -0.2794)
				(xy -0.5334 -0.2794) (xy -0.5334 -0.254) (xy -0.635 -0.254) (xy -0.635 0.254) (xy -0.5334 0.254)
				(xy -0.5334 0.2794)
			)
			(stroke
				(width 0)
				(type default)
			)
			(fill no)
			(layer "B.CrtYd")
		)
		(pad "1" smd rect
			(at -0.40005 0 90)
			(size 0.4572 0.508)
			(layers "B.Cu" "B.Mask" "B.Paste")
			(net "CPLD_UART_RI_P4_LS_N")
		)
		(pad "2" smd rect
			(at 0.40005 0 90)
			(size 0.4572 0.508)
			(layers "B.Cu" "B.Mask" "B.Paste")
			(net "CPLD_UART_RI_P4_N")
		)
	)
	(footprint ""
		(layer "B.Cu")
		(at 140.507466 -41.285414 180)
		(property "Reference" "R1189"
			(at 2.019808 -18.796254 0)
			(unlocked yes)
			(layer "B.SilkS")
			(effects
				(font
					(size 0.7874 0.5842)
					(thickness 0.1524)
				)
				(justify left mirror)
			)
		)
		(property "Value" ""
			(at 0 0 0)
			(layer "B.Fab")
			(effects
				(font
					(size 1.27 1.27)
				)
				(justify mirror)
			)
		)
		(duplicate_pad_numbers_are_jumpers no)
		(fp_line
			(start 0.7874 0.4064)
			(end 0.7874 -0.4064)
			(stroke
				(width 0.1524)
				(type default)
			)
			(layer "B.SilkS")
		)
		(fp_line
			(start 0.7874 -0.4064)
			(end -0.7874 -0.4064)
			(stroke
				(width 0.1524)
				(type default)
			)
			(layer "B.SilkS")
		)
		(fp_line
			(start -0.7874 0.4064)
			(end 0.7874 0.4064)
			(stroke
				(width 0.1524)
				(type default)
			)
			(layer "B.SilkS")
		)
		(fp_line
			(start -0.7874 -0.4064)
			(end -0.7874 0.4064)
			(stroke
				(width 0.1524)
				(type default)
			)
			(layer "B.SilkS")
		)
		(fp_poly
			(pts
				(xy 0.508 0.2794) (xy 0.508 0.2286) (xy 0.635 0.2286) (xy 0.635 -0.254) (xy 0.5334 -0.254) (xy 0.5334 -0.2794)
				(xy -0.5334 -0.2794) (xy -0.5334 -0.254) (xy -0.635 -0.254) (xy -0.635 0.254) (xy -0.5334 0.254)
				(xy -0.5334 0.2794)
			)
			(stroke
				(width 0)
				(type default)
			)
			(fill no)
			(layer "B.CrtYd")
		)
		(pad "1" smd rect
			(at -0.40005 0)
			(size 0.4572 0.508)
			(layers "B.Cu" "B.Mask" "B.Paste")
			(net "SIO_JTAG_CPLD2_TCK_R")
		)
		(pad "2" smd rect
			(at 0.40005 0)
			(size 0.4572 0.508)
			(layers "B.Cu" "B.Mask" "B.Paste")
			(net "SIO_JTAG_CPLD2_TCK")
		)
	)
)
